FILE_TYPE=LIBRARY_PARTS;
primitive '9SQ440NQQI8';
  pin
    '25M1#':
      PIN_NUMBER='(A2,0)';
      OUTPUT_LOAD='(1.0,-1.0)';
    'EPAD':
      PIN_NUMBER='(C1,0)';
      PINUSE='POWER';
      NO_LOAD_CHECK='Both';
      NO_IO_CHECK='Both';
      NO_ASSERT_CHECK='TRUE';
      NO_DIR_CHECK='TRUE';
      ALLOW_CONNECT='TRUE';
    'GNDXTAL':
      PIN_NUMBER='(A14,0)';
      PINUSE='POWER';
      NO_LOAD_CHECK='Both';
      NO_IO_CHECK='Both';
      NO_ASSERT_CHECK='TRUE';
      NO_DIR_CHECK='TRUE';
      ALLOW_CONNECT='TRUE';
    'SMB_ADR1_TRI':
      PIN_NUMBER='(B9,0)';
      INPUT_LOAD='(-0.01,0.01)';
    'SBI_CLK':
      PIN_NUMBER='(A54,0)';
      INPUT_LOAD='(-0.01,0.01)';
    'SHFT_LD#':
      PIN_NUMBER='(B42,0)';
      INPUT_LOAD='(-0.01,0.01)';
    'OE2#':
      PIN_NUMBER='(A29,0)';
      INPUT_LOAD='(-0.01,0.01)';
    'OE3#':
      PIN_NUMBER='(A26,0)';
      INPUT_LOAD='(-0.01,0.01)';
    'OE4#':
      PIN_NUMBER='(B19,0)';
      INPUT_LOAD='(-0.01,0.01)';
    'OE1#':
      PIN_NUMBER='(A30,0)';
      INPUT_LOAD='(-0.01,0.01)';
    'OE5#':
      PIN_NUMBER='(B15,0)';
      INPUT_LOAD='(-0.01,0.01)';
    '25M0#':
      PIN_NUMBER='(A4,0)';
      OUTPUT_LOAD='(1.0,-1.0)';
    '25M0':
      PIN_NUMBER='(A5,0)';
      OUTPUT_LOAD='(1.0,-1.0)';
    '25M1':
      PIN_NUMBER='(A3,0)';
      OUTPUT_LOAD='(1.0,-1.0)';
    '25M2#':
      PIN_NUMBER='(A55,0)';
      OUTPUT_LOAD='(1.0,-1.0)';
    '25M2':
      PIN_NUMBER='(A56,0)';
      OUTPUT_LOAD='(1.0,-1.0)';
    '25MPG':
      PIN_NUMBER='(A1,0)';
      INPUT_LOAD='(-0.01,0.01)';
    '100M0#':
      PIN_NUMBER='(A33,0)';
      OUTPUT_LOAD='(1.0,-1.0)';
    '100M0':
      PIN_NUMBER='(A34,0)';
      OUTPUT_LOAD='(1.0,-1.0)';
    '100M1#':
      PIN_NUMBER='(A31,0)';
      OUTPUT_LOAD='(1.0,-1.0)';
    '100M1':
      PIN_NUMBER='(A32,0)';
      OUTPUT_LOAD='(1.0,-1.0)';
    '100M2#':
      PIN_NUMBER='(A27,0)';
      OUTPUT_LOAD='(1.0,-1.0)';
    '100M2':
      PIN_NUMBER='(A28,0)';
      OUTPUT_LOAD='(1.0,-1.0)';
    '100M3#':
      PIN_NUMBER='(A24,0)';
      OUTPUT_LOAD='(1.0,-1.0)';
    '100M3':
      PIN_NUMBER='(A25,0)';
      OUTPUT_LOAD='(1.0,-1.0)';
    '100M4#':
      PIN_NUMBER='(A22,0)';
      OUTPUT_LOAD='(1.0,-1.0)';
    '100M4':
      PIN_NUMBER='(A23,0)';
      OUTPUT_LOAD='(1.0,-1.0)';
    '100M5#':
      PIN_NUMBER='(A20,0)';
      OUTPUT_LOAD='(1.0,-1.0)';
    '100M5':
      PIN_NUMBER='(A21,0)';
      OUTPUT_LOAD='(1.0,-1.0)';
    '100M6#':
      PIN_NUMBER='(A18,0)';
      OUTPUT_LOAD='(1.0,-1.0)';
    '100M6':
      PIN_NUMBER='(A19,0)';
      OUTPUT_LOAD='(1.0,-1.0)';
    'GNDS':
      PIN_NUMBER='(B10,0)';
      PINUSE='POWER';
      NO_LOAD_CHECK='Both';
      NO_IO_CHECK='Both';
      NO_ASSERT_CHECK='TRUE';
      NO_DIR_CHECK='TRUE';
      ALLOW_CONNECT='TRUE';
    'MXCK0#':
      PIN_NUMBER='(A51,0)';
      OUTPUT_LOAD='(1.0,-1.0)';
    'MXCK0':
      PIN_NUMBER='(A52,0)';
      OUTPUT_LOAD='(1.0,-1.0)';
    'MXCK1#':
      PIN_NUMBER='(A49,0)';
      OUTPUT_LOAD='(1.0,-1.0)';
    'MXCK1':
      PIN_NUMBER='(A50,0)';
      OUTPUT_LOAD='(1.0,-1.0)';
    'MXCK2#':
      PIN_NUMBER='(A47,0)';
      OUTPUT_LOAD='(1.0,-1.0)';
    'MXCK2':
      PIN_NUMBER='(A48,0)';
      OUTPUT_LOAD='(1.0,-1.0)';
    'MXCK3#':
      PIN_NUMBER='(A45,0)';
      OUTPUT_LOAD='(1.0,-1.0)';
    'MXCK3':
      PIN_NUMBER='(A46,0)';
      OUTPUT_LOAD='(1.0,-1.0)';
    'MXCK4#':
      PIN_NUMBER='(A43,0)';
      OUTPUT_LOAD='(1.0,-1.0)';
    'MXCK4':
      PIN_NUMBER='(A44,0)';
      OUTPUT_LOAD='(1.0,-1.0)';
    'MXCK5#':
      PIN_NUMBER='(A41,0)';
      OUTPUT_LOAD='(1.0,-1.0)';
    'MXCK5':
      PIN_NUMBER='(A42,0)';
      OUTPUT_LOAD='(1.0,-1.0)';
    'MXCK6#':
      PIN_NUMBER='(A39,0)';
      OUTPUT_LOAD='(1.0,-1.0)';
    'MXCK6':
      PIN_NUMBER='(A40,0)';
      OUTPUT_LOAD='(1.0,-1.0)';
    'MXCK7#':
      PIN_NUMBER='(A37,0)';
      OUTPUT_LOAD='(1.0,-1.0)';
    'MXCK7':
      PIN_NUMBER='(A38,0)';
      OUTPUT_LOAD='(1.0,-1.0)';
    'MXCK8#':
      PIN_NUMBER='(A35,0)';
      OUTPUT_LOAD='(1.0,-1.0)';
    'MXCK8':
      PIN_NUMBER='(A36,0)';
      OUTPUT_LOAD='(1.0,-1.0)';
    'MXCK_SEL_100M#':
      PIN_NUMBER='(B38,0)';
      INPUT_LOAD='(-0.01,0.01)';
    'NVGND':
      PIN_NUMBER='(B12,0)';
      PINUSE='POWER';
      NO_LOAD_CHECK='Both';
      NO_IO_CHECK='Both';
      NO_ASSERT_CHECK='TRUE';
      NO_DIR_CHECK='TRUE';
      ALLOW_CONNECT='TRUE';
    'OE0#':
      PIN_NUMBER='(B27,0)';
      INPUT_LOAD='(-0.01,0.01)';
    'OE6#':
      PIN_NUMBER='(B14,0)';
      INPUT_LOAD='(-0.01,0.01)';
    'PFT_IN#':
      PIN_NUMBER='(A9,0)';
      INPUT_LOAD='(-0.01,0.01)';
    'PFT_IN':
      PIN_NUMBER='(A8,0)';
      INPUT_LOAD='(-0.01,0.01)';
    'PFT_LOST#':
      PIN_NUMBER='(B4,0)';
      OUTPUT_LOAD='(1.0,-1.0)';
    'PFT_OUT#':
      PIN_NUMBER='(A7,0)';
      OUTPUT_LOAD='(1.0,-1.0)';
    'PFT_OUT':
      PIN_NUMBER='(A6,0)';
      OUTPUT_LOAD='(1.0,-1.0)';
    'PWRGD||PWRDN#':
      PIN_NUMBER='(A17,0)';
      INPUT_LOAD='(-0.01,0.01)';
    'SBI_IN':
      PIN_NUMBER='(B43,0)';
      INPUT_LOAD='(-0.01,0.01)';
    'SBI_OUT':
      PIN_NUMBER='(A53,0)';
      OUTPUT_LOAD='(1.0,-1.0)';
    'SCLK':
      PIN_NUMBER='(A10,0)';
      INPUT_LOAD='(-0.01,0.01)';
    'SMBDATTA':
      PIN_NUMBER='(B8,0)';
      BIDIRECTIONAL='TRUE';
      INPUT_LOAD='(-0.01,0.01)';
      OUTPUT_LOAD='(1.0,-1.0)';
    'SMB_ADR0_TRI':
      PIN_NUMBER='(A11,0)';
      INPUT_LOAD='(-0.01,0.01)';
    'SS_EN_TRI':
      PIN_NUMBER='(A16,0)';
      INPUT_LOAD='(-0.01,0.01)';
    'VDDA25M':
      PIN_NUMBER='(B1,0)';
      PINUSE='POWER';
      NO_LOAD_CHECK='Both';
      NO_IO_CHECK='Both';
      NO_ASSERT_CHECK='TRUE';
      NO_DIR_CHECK='TRUE';
      ALLOW_CONNECT='TRUE';
    'VDDA100M':
      PIN_NUMBER='(B17,0)';
      PINUSE='POWER';
      NO_LOAD_CHECK='Both';
      NO_IO_CHECK='Both';
      NO_ASSERT_CHECK='TRUE';
      NO_DIR_CHECK='TRUE';
      ALLOW_CONNECT='TRUE';
    'VDDPT':
      PIN_NUMBER='(B6,0)';
      PINUSE='POWER';
      NO_LOAD_CHECK='Both';
      NO_IO_CHECK='Both';
      NO_ASSERT_CHECK='TRUE';
      NO_DIR_CHECK='TRUE';
      ALLOW_CONNECT='TRUE';
    'VDDXTAL':
      PIN_NUMBER='(A12,0)';
      PINUSE='POWER';
      NO_LOAD_CHECK='Both';
      NO_IO_CHECK='Both';
      NO_ASSERT_CHECK='TRUE';
      NO_DIR_CHECK='TRUE';
      ALLOW_CONNECT='TRUE';
    'XIN_CLKIN':
      PIN_NUMBER='(A13,0)';
      INPUT_LOAD='(-0.01,0.01)';
    'XOUT':
      PIN_NUMBER='(B11,0)';
      OUTPUT_LOAD='(1.0,-1.0)';
    'VDDMXCK_B29':
      PIN_NUMBER='(B29,0)';
      PINUSE='POWER';
      NO_LOAD_CHECK='Both';
      NO_IO_CHECK='Both';
      NO_ASSERT_CHECK='TRUE';
      NO_DIR_CHECK='TRUE';
      ALLOW_CONNECT='TRUE';
    'VDDMXCK_B32':
      PIN_NUMBER='(B32,0)';
      PINUSE='POWER';
      NO_LOAD_CHECK='Both';
      NO_IO_CHECK='Both';
      NO_ASSERT_CHECK='TRUE';
      NO_DIR_CHECK='TRUE';
      ALLOW_CONNECT='TRUE';
    'VDDMXCK_B35':
      PIN_NUMBER='(B35,0)';
      PINUSE='POWER';
      NO_LOAD_CHECK='Both';
      NO_IO_CHECK='Both';
      NO_ASSERT_CHECK='TRUE';
      NO_DIR_CHECK='TRUE';
      ALLOW_CONNECT='TRUE';
    'VDDMXCK_B40':
      PIN_NUMBER='(B40,0)';
      PINUSE='POWER';
      NO_LOAD_CHECK='Both';
      NO_IO_CHECK='Both';
      NO_ASSERT_CHECK='TRUE';
      NO_DIR_CHECK='TRUE';
      ALLOW_CONNECT='TRUE';
    'VDD100M_B21':
      PIN_NUMBER='(B21,0)';
      PINUSE='POWER';
      NO_LOAD_CHECK='Both';
      NO_IO_CHECK='Both';
      NO_ASSERT_CHECK='TRUE';
      NO_DIR_CHECK='TRUE';
      ALLOW_CONNECT='TRUE';
    'VDD100M_B23':
      PIN_NUMBER='(B23,0)';
      PINUSE='POWER';
      NO_LOAD_CHECK='Both';
      NO_IO_CHECK='Both';
      NO_ASSERT_CHECK='TRUE';
      NO_DIR_CHECK='TRUE';
      ALLOW_CONNECT='TRUE';
    'NC_B22':
      PIN_NUMBER='(0,B22)';
      OUTPUT_TYPE='(TS,TS)';
      INPUT_LOAD='(-0.01,0.01)';
      OUTPUT_LOAD='(1.0,-1.0)';
    'NC_B20':
      PIN_NUMBER='(0,B20)';
      OUTPUT_TYPE='(TS,TS)';
      INPUT_LOAD='(-0.01,0.01)';
      OUTPUT_LOAD='(1.0,-1.0)';
    'NC_B18':
      PIN_NUMBER='(0,B18)';
      OUTPUT_TYPE='(TS,TS)';
      INPUT_LOAD='(-0.01,0.01)';
      OUTPUT_LOAD='(1.0,-1.0)';
    'NC_B16':
      PIN_NUMBER='(0,B16)';
      OUTPUT_TYPE='(TS,TS)';
      INPUT_LOAD='(-0.01,0.01)';
      OUTPUT_LOAD='(1.0,-1.0)';
    'NC_B13':
      PIN_NUMBER='(0,B13)';
      OUTPUT_TYPE='(TS,TS)';
      INPUT_LOAD='(-0.01,0.01)';
      OUTPUT_LOAD='(1.0,-1.0)';
    'NC_B7':
      PIN_NUMBER='(0,B7)';
      OUTPUT_TYPE='(TS,TS)';
      INPUT_LOAD='(-0.01,0.01)';
      OUTPUT_LOAD='(1.0,-1.0)';
    'NC_B5':
      PIN_NUMBER='(0,B5)';
      OUTPUT_TYPE='(TS,TS)';
      INPUT_LOAD='(-0.01,0.01)';
      OUTPUT_LOAD='(1.0,-1.0)';
    'NC_B3':
      PIN_NUMBER='(0,B3)';
      OUTPUT_TYPE='(TS,TS)';
      INPUT_LOAD='(-0.01,0.01)';
      OUTPUT_LOAD='(1.0,-1.0)';
    'NC_B2':
      PIN_NUMBER='(0,B2)';
      OUTPUT_TYPE='(TS,TS)';
      INPUT_LOAD='(-0.01,0.01)';
      OUTPUT_LOAD='(1.0,-1.0)';
    'NC_A15':
      PIN_NUMBER='(0,A15)';
      OUTPUT_TYPE='(TS,TS)';
      INPUT_LOAD='(-0.01,0.01)';
      OUTPUT_LOAD='(1.0,-1.0)';
    'NC_B24':
      PIN_NUMBER='(0,B24)';
      OUTPUT_TYPE='(TS,TS)';
      INPUT_LOAD='(-0.01,0.01)';
      OUTPUT_LOAD='(1.0,-1.0)';
    'NC_B25':
      PIN_NUMBER='(0,B25)';
      OUTPUT_TYPE='(TS,TS)';
      INPUT_LOAD='(-0.01,0.01)';
      OUTPUT_LOAD='(1.0,-1.0)';
    'NC_B26':
      PIN_NUMBER='(0,B26)';
      OUTPUT_TYPE='(TS,TS)';
      INPUT_LOAD='(-0.01,0.01)';
      OUTPUT_LOAD='(1.0,-1.0)';
    'NC_B28':
      PIN_NUMBER='(0,B28)';
      OUTPUT_TYPE='(TS,TS)';
      INPUT_LOAD='(-0.01,0.01)';
      OUTPUT_LOAD='(1.0,-1.0)';
    'NC_B30':
      PIN_NUMBER='(0,B30)';
      OUTPUT_TYPE='(TS,TS)';
      INPUT_LOAD='(-0.01,0.01)';
      OUTPUT_LOAD='(1.0,-1.0)';
    'NC_B31':
      PIN_NUMBER='(0,B31)';
      OUTPUT_TYPE='(TS,TS)';
      INPUT_LOAD='(-0.01,0.01)';
      OUTPUT_LOAD='(1.0,-1.0)';
    'NC_B33':
      PIN_NUMBER='(0,B33)';
      OUTPUT_TYPE='(TS,TS)';
      INPUT_LOAD='(-0.01,0.01)';
      OUTPUT_LOAD='(1.0,-1.0)';
    'NC_B34':
      PIN_NUMBER='(0,B34)';
      OUTPUT_TYPE='(TS,TS)';
      INPUT_LOAD='(-0.01,0.01)';
      OUTPUT_LOAD='(1.0,-1.0)';
    'NC_B36':
      PIN_NUMBER='(0,B36)';
      OUTPUT_TYPE='(TS,TS)';
      INPUT_LOAD='(-0.01,0.01)';
      OUTPUT_LOAD='(1.0,-1.0)';
    'NC_B37':
      PIN_NUMBER='(0,B37)';
      OUTPUT_TYPE='(TS,TS)';
      INPUT_LOAD='(-0.01,0.01)';
      OUTPUT_LOAD='(1.0,-1.0)';
    'NC_B39':
      PIN_NUMBER='(0,B39)';
      OUTPUT_TYPE='(TS,TS)';
      INPUT_LOAD='(-0.01,0.01)';
      OUTPUT_LOAD='(1.0,-1.0)';
    'NC_B41':
      PIN_NUMBER='(0,B41)';
      OUTPUT_TYPE='(TS,TS)';
      INPUT_LOAD='(-0.01,0.01)';
      OUTPUT_LOAD='(1.0,-1.0)';
    'NC_B44':
      PIN_NUMBER='(0,B44)';
      OUTPUT_TYPE='(TS,TS)';
      INPUT_LOAD='(-0.01,0.01)';
      OUTPUT_LOAD='(1.0,-1.0)';
  end_pin;
  body
    PART_NAME='9SQ440NQQI8';
    BODY_NAME='9SQ440NQQI8';
    PHYS_DES_PREFIX='U';
    CLASS='IC';
  end_body;
end_primitive;

END.
